(kicad_pcb
	(version 20221018)
	(generator pcbnew)
	(general
    (thickness 1.62)
  )
	(paper "A4")
	(title_block
    (title "ECP5 - Datacenter Secure Control Module (DC-SCM)")
    (date "2024-07-01")
    (rev "1.2.1")
		(comment 9 "footprint 50 of 506 (U21), pads 101-203 of 756")
	)
	(layers
    (0 "F.Cu" signal)
    (1 "In1.Cu" power)
    (2 "In2.Cu" signal)
    (3 "In3.Cu" power)
    (4 "In4.Cu" power)
    (5 "In5.Cu" signal)
    (6 "In6.Cu" power)
    (31 "B.Cu" signal)
    (32 "B.Adhes" user "B.Adhesive")
    (33 "F.Adhes" user "F.Adhesive")
    (34 "B.Paste" user)
    (35 "F.Paste" user)
    (36 "B.SilkS" user "B.Silkscreen")
    (37 "F.SilkS" user "F.Silkscreen")
    (38 "B.Mask" user)
    (39 "F.Mask" user)
    (40 "Dwgs.User" user "User.Drawings")
    (41 "Cmts.User" user "User.Comments")
    (42 "Eco1.User" user "User.Eco1")
    (43 "Eco2.User" user "User.Eco2")
    (44 "Edge.Cuts" user)
    (45 "Margin" user)
    (46 "B.CrtYd" user "B.Courtyard")
    (47 "F.CrtYd" user "F.Courtyard")
    (48 "B.Fab" user)
    (49 "F.Fab" user)
  )
	(footprint "antmicro-footprints:BGA-1024-756_27x27mm_Layout32x32_P0.8mm" locked
    (layer "F.Cu")
    (at 104.4 120.55)
    (property "Author" "Antmicro")
    (property "License" "Apache-2.0")
    (property "MPN" "LFE5UM5G-85F-8BG756C")
    (property "Manufacturer" "Lattice Semiconductor")
    (property "Sheetfile" "fpga-power-supply.kicad_sch")
    (property "Sheetname" "FPGA power supply")
    (property "ki_description" "ECP5-5G Field Programmable Gate Array")
    (property "ki_keywords" "SMT, FPGA, IC")
    (attr smd)
    (fp_text reference "U21" (at -12.97 -14.53) (layer "F.SilkS")
        (effects (font (size 0.7 0.7) (thickness 0.127)))
    )
    (fp_text value "ECP5UM5G_85_CABGA756" (at 0 14.5) (layer "F.Fab")
        (effects (font (size 1 1) (thickness 0.15)))
    )
    (pad "AD5" smd circle locked (at -9.2 6) (size 0.4 0.4) (layers "F.Cu" "F.Paste" "F.Mask")
      (net 1 "GND") (pinfunction "GND") (pintype "passive"))
    (pad "AD6" smd circle locked (at -8.4 6) (size 0.4 0.4) (layers "F.Cu" "F.Paste" "F.Mask")
      (net 191 "DDR3_DQ1") (pinfunction "PL80A") (pintype "bidirectional"))
    (pad "AD7" smd circle locked (at -7.6 6) (size 0.4 0.4) (layers "F.Cu" "F.Paste" "F.Mask")
      (net 178 "DDR3_DM0") (pinfunction "PL77D") (pintype "bidirectional"))
    (pad "AD26" smd circle locked (at 7.6 6) (size 0.4 0.4) (layers "F.Cu" "F.Paste" "F.Mask")
      (net 561 "unconnected-(U21E-PR77D-PadAD26)") (pinfunction "PR77D") (pintype "bidirectional+no_connect"))
    (pad "AD27" smd circle locked (at 8.4 6) (size 0.4 0.4) (layers "F.Cu" "F.Paste" "F.Mask")
      (net 562 "unconnected-(U21E-PR80A-PadAD27)") (pinfunction "PR80A") (pintype "bidirectional+no_connect"))
    (pad "AD28" smd circle locked (at 9.2 6) (size 0.4 0.4) (layers "F.Cu" "F.Paste" "F.Mask")
      (net 1 "GND") (pinfunction "GND") (pintype "passive"))
    (pad "AD29" smd circle locked (at 10 6) (size 0.4 0.4) (layers "F.Cu" "F.Paste" "F.Mask")
      (net 563 "unconnected-(U21E-PR83D-PadAD29)") (pinfunction "PR83D") (pintype "bidirectional+no_connect"))
    (pad "AD30" smd circle locked (at 10.8 6) (size 0.4 0.4) (layers "F.Cu" "F.Paste" "F.Mask")
      (net 564 "unconnected-(U21E-PR86C-PadAD30)") (pinfunction "PR86C") (pintype "bidirectional+no_connect"))
    (pad "AD31" smd circle locked (at 11.6 6) (size 0.4 0.4) (layers "F.Cu" "F.Paste" "F.Mask")
      (net 1 "GND") (pinfunction "GND") (pintype "passive"))
    (pad "AD32" smd circle locked (at 12.4 6) (size 0.4 0.4) (layers "F.Cu" "F.Paste" "F.Mask")
      (net 327 "ULPI2_D2") (pinfunction "PR92C") (pintype "bidirectional"))
    (pad "AE1" smd circle locked (at -12.4 6.8) (size 0.4 0.4) (layers "F.Cu" "F.Paste" "F.Mask")
      (net 182 "DDR3_DQ9") (pinfunction "PL92D") (pintype "bidirectional"))
    (pad "AE2" smd circle locked (at -11.6 6.8) (size 0.4 0.4) (layers "F.Cu" "F.Paste" "F.Mask")
      (net 181 "DDR3_DQ14") (pinfunction "PL89D") (pintype "bidirectional"))
    (pad "AE3" smd circle locked (at -10.8 6.8) (size 0.4 0.4) (layers "F.Cu" "F.Paste" "F.Mask")
      (net 195 "DDR3_DQ8") (pinfunction "PL86D") (pintype "bidirectional"))
    (pad "AE4" smd circle locked (at -10 6.8) (size 0.4 0.4) (layers "F.Cu" "F.Paste" "F.Mask")
      (net 253 "DDR3_A5") (pinfunction "PL80D") (pintype "bidirectional"))
    (pad "AE5" smd circle locked (at -9.2 6.8) (size 0.4 0.4) (layers "F.Cu" "F.Paste" "F.Mask")
      (net 193 "DDR3_DQ3") (pinfunction "PL80C") (pintype "bidirectional"))
    (pad "AE6" smd circle locked (at -8.4 6.8) (size 0.4 0.4) (layers "F.Cu" "F.Paste" "F.Mask")
      (net 255 "DDR3_A3") (pinfunction "PL80B") (pintype "bidirectional"))
    (pad "AE7" smd circle locked (at -7.6 6.8) (size 0.4 0.4) (layers "F.Cu" "F.Paste" "F.Mask")
      (net 565 "unconnected-(U21A-NC-PadAE7)") (pinfunction "NC") (pintype "no_connect"))
    (pad "AE26" smd circle locked (at 7.6 6.8) (size 0.4 0.4) (layers "F.Cu" "F.Paste" "F.Mask")
      (net 566 "unconnected-(U21A-NC-PadAE26)") (pinfunction "NC") (pintype "no_connect"))
    (pad "AE27" smd circle locked (at 8.4 6.8) (size 0.4 0.4) (layers "F.Cu" "F.Paste" "F.Mask")
      (net 567 "unconnected-(U21E-PR80B-PadAE27)") (pinfunction "PR80B") (pintype "bidirectional+no_connect"))
    (pad "AE28" smd circle locked (at 9.2 6.8) (size 0.4 0.4) (layers "F.Cu" "F.Paste" "F.Mask")
      (net 568 "unconnected-(U21E-PR80C-PadAE28)") (pinfunction "PR80C") (pintype "bidirectional+no_connect"))
    (pad "AE29" smd circle locked (at 10 6.8) (size 0.4 0.4) (layers "F.Cu" "F.Paste" "F.Mask")
      (net 569 "unconnected-(U21E-PR80D-PadAE29)") (pinfunction "PR80D") (pintype "bidirectional+no_connect"))
    (pad "AE30" smd circle locked (at 10.8 6.8) (size 0.4 0.4) (layers "F.Cu" "F.Paste" "F.Mask")
      (net 570 "unconnected-(U21E-PR86D-PadAE30)") (pinfunction "PR86D") (pintype "bidirectional+no_connect"))
    (pad "AE31" smd circle locked (at 11.6 6.8) (size 0.4 0.4) (layers "F.Cu" "F.Paste" "F.Mask")
      (net 328 "ULPI2_D1") (pinfunction "PR89D") (pintype "bidirectional"))
    (pad "AE32" smd circle locked (at 12.4 6.8) (size 0.4 0.4) (layers "F.Cu" "F.Paste" "F.Mask")
      (net 329 "ULPI2_D0") (pinfunction "PR92D") (pintype "bidirectional"))
    (pad "AF11" smd circle locked (at -4.4 7.6) (size 0.4 0.4) (layers "F.Cu" "F.Paste" "F.Mask")
      (net 1 "GND") (pinfunction "GND") (pintype "passive"))
    (pad "AF12" smd circle locked (at -3.6 7.6) (size 0.4 0.4) (layers "F.Cu" "F.Paste" "F.Mask")
      (net 1 "GND") (pinfunction "GND") (pintype "passive"))
    (pad "AF14" smd circle locked (at -2 7.6) (size 0.4 0.4) (layers "F.Cu" "F.Paste" "F.Mask")
      (net 1 "GND") (pinfunction "GND") (pintype "passive"))
    (pad "AF15" smd circle locked (at -1.2 7.6) (size 0.4 0.4) (layers "F.Cu" "F.Paste" "F.Mask")
      (net 1 "GND") (pinfunction "GND") (pintype "passive"))
    (pad "AF16" smd circle locked (at -0.4 7.6) (size 0.4 0.4) (layers "F.Cu" "F.Paste" "F.Mask")
      (net 1 "GND") (pinfunction "GND") (pintype "passive"))
    (pad "AF17" smd circle locked (at 0.4 7.6) (size 0.4 0.4) (layers "F.Cu" "F.Paste" "F.Mask")
      (net 1 "GND") (pinfunction "GND") (pintype "passive"))
    (pad "AF19" smd circle locked (at 2 7.6) (size 0.4 0.4) (layers "F.Cu" "F.Paste" "F.Mask")
      (net 1 "GND") (pinfunction "GND") (pintype "passive"))
    (pad "AF20" smd circle locked (at 2.8 7.6) (size 0.4 0.4) (layers "F.Cu" "F.Paste" "F.Mask")
      (net 1 "GND") (pinfunction "GND") (pintype "passive"))
    (pad "AF22" smd circle locked (at 4.4 7.6) (size 0.4 0.4) (layers "F.Cu" "F.Paste" "F.Mask")
      (net 303 "/FPGA power supply/VCCA1") (pinfunction "VCCA1") (pintype "power_in"))
    (pad "AF23" smd circle locked (at 5.2 7.6) (size 0.4 0.4) (layers "F.Cu" "F.Paste" "F.Mask")
      (net 1 "GND") (pinfunction "GND") (pintype "passive"))
    (pad "AG1" smd circle locked (at -12.4 8.4) (size 0.4 0.4) (layers "F.Cu" "F.Paste" "F.Mask")
      (net 427 "Net-(U21I-PB4A)") (pinfunction "PB4A") (pintype "bidirectional"))
    (pad "AG2" smd circle locked (at -11.6 8.4) (size 0.4 0.4) (layers "F.Cu" "F.Paste" "F.Mask")
      (net 571 "unconnected-(U21A-NC-PadAG2)") (pinfunction "NC") (pintype "no_connect"))
    (pad "AG3" smd circle locked (at -10.8 8.4) (size 0.4 0.4) (layers "F.Cu" "F.Paste" "F.Mask")
      (net 271 "ROT_QSPI_CS_N") (pinfunction "PB13A") (pintype "bidirectional"))
    (pad "AG4" smd circle locked (at -10 8.4) (size 0.4 0.4) (layers "F.Cu" "F.Paste" "F.Mask")
      (net 269 "INIT_N") (pinfunction "INITN") (pintype "bidirectional"))
    (pad "AG5" smd circle locked (at -9.2 8.4) (size 0.4 0.4) (layers "F.Cu" "F.Paste" "F.Mask")
      (net 20 "JTAG_TDO") (pinfunction "TDO") (pintype "bidirectional"))
    (pad "AG9" smd circle locked (at -6 8.4) (size 0.4 0.4) (layers "F.Cu" "F.Paste" "F.Mask")
      (net 302 "/FPGA power supply/VCCA0") (pinfunction "VCCA0") (pintype "passive"))
    (pad "AG11" smd circle locked (at -4.4 8.4) (size 0.4 0.4) (layers "F.Cu" "F.Paste" "F.Mask")
      (net 1 "GND") (pinfunction "GND") (pintype "passive"))
    (pad "AG12" smd circle locked (at -3.6 8.4) (size 0.4 0.4) (layers "F.Cu" "F.Paste" "F.Mask")
      (net 302 "/FPGA power supply/VCCA0") (pinfunction "VCCA0") (pintype "power_in"))
    (pad "AG14" smd circle locked (at -2 8.4) (size 0.4 0.4) (layers "F.Cu" "F.Paste" "F.Mask")
      (net 1 "GND") (pinfunction "GND") (pintype "passive"))
    (pad "AG15" smd circle locked (at -1.2 8.4) (size 0.4 0.4) (layers "F.Cu" "F.Paste" "F.Mask")
      (net 1 "GND") (pinfunction "GND") (pintype "passive"))
    (pad "AG16" smd circle locked (at -0.4 8.4) (size 0.4 0.4) (layers "F.Cu" "F.Paste" "F.Mask")
      (net 1 "GND") (pinfunction "GND") (pintype "passive"))
    (pad "AG17" smd circle locked (at 0.4 8.4) (size 0.4 0.4) (layers "F.Cu" "F.Paste" "F.Mask")
      (net 1 "GND") (pinfunction "GND") (pintype "passive"))
    (pad "AG19" smd circle locked (at 2 8.4) (size 0.4 0.4) (layers "F.Cu" "F.Paste" "F.Mask")
      (net 303 "/FPGA power supply/VCCA1") (pinfunction "VCCA1") (pintype "passive"))
    (pad "AG20" smd circle locked (at 2.8 8.4) (size 0.4 0.4) (layers "F.Cu" "F.Paste" "F.Mask")
      (net 1 "GND") (pinfunction "GND") (pintype "passive"))
    (pad "AG22" smd circle locked (at 4.4 8.4) (size 0.4 0.4) (layers "F.Cu" "F.Paste" "F.Mask")
      (net 303 "/FPGA power supply/VCCA1") (pinfunction "VCCA1") (pintype "passive"))
    (pad "AG23" smd circle locked (at 5.2 8.4) (size 0.4 0.4) (layers "F.Cu" "F.Paste" "F.Mask")
      (net 1 "GND") (pinfunction "GND") (pintype "passive"))
    (pad "AG24" smd circle locked (at 6 8.4) (size 0.4 0.4) (layers "F.Cu" "F.Paste" "F.Mask")
      (net 572 "unconnected-(U21A-NC-PadAG24)") (pinfunction "NC") (pintype "no_connect"))
    (pad "AG28" smd circle locked (at 9.2 8.4) (size 0.4 0.4) (layers "F.Cu" "F.Paste" "F.Mask")
      (net 94 "QSPI1_D0") (pinfunction "PB110A") (pintype "bidirectional"))
    (pad "AG29" smd circle locked (at 10 8.4) (size 0.4 0.4) (layers "F.Cu" "F.Paste" "F.Mask")
      (net 95 "QSPI1_D1") (pinfunction "PB110B") (pintype "bidirectional"))
    (pad "AG30" smd circle locked (at 10.8 8.4) (size 0.4 0.4) (layers "F.Cu" "F.Paste" "F.Mask")
      (net 96 "QSPI1_D2") (pinfunction "PB114B") (pintype "bidirectional"))
    (pad "AG31" smd circle locked (at 11.6 8.4) (size 0.4 0.4) (layers "F.Cu" "F.Paste" "F.Mask")
      (net 573 "unconnected-(U21A-NC-PadAG31)") (pinfunction "NC") (pintype "no_connect"))
    (pad "AG32" smd circle locked (at 12.4 8.4) (size 0.4 0.4) (layers "F.Cu" "F.Paste" "F.Mask")
      (net 97 "QSPI1_D3") (pinfunction "PB119B") (pintype "bidirectional"))
    (pad "AH1" smd circle locked (at -12.4 9.2) (size 0.4 0.4) (layers "F.Cu" "F.Paste" "F.Mask")
      (net 428 "Net-(U21I-PB4B)") (pinfunction "PB4B") (pintype "bidirectional"))
    (pad "AH2" smd circle locked (at -11.6 9.2) (size 0.4 0.4) (layers "F.Cu" "F.Paste" "F.Mask")
      (net 1 "GND") (pinfunction "GND") (pintype "passive"))
    (pad "AH3" smd circle locked (at -10.8 9.2) (size 0.4 0.4) (layers "F.Cu" "F.Paste" "F.Mask")
      (net 574 "unconnected-(U21I-PB13B-PadAH3)") (pinfunction "PB13B") (pintype "bidirectional+no_connect"))
    (pad "AH4" smd circle locked (at -10 9.2) (size 0.4 0.4) (layers "F.Cu" "F.Paste" "F.Mask")
      (net 268 "PROGRAM_N") (pinfunction "PROGRAMN") (pintype "bidirectional"))
    (pad "AH5" smd circle locked (at -9.2 9.2) (size 0.4 0.4) (layers "F.Cu" "F.Paste" "F.Mask")
      (net 1 "GND") (pinfunction "GND") (pintype "passive"))
    (pad "AH7" smd circle locked (at -7.6 9.2) (size 0.4 0.4) (layers "F.Cu" "F.Paste" "F.Mask")
      (net 1 "GND") (pinfunction "GND") (pintype "passive"))
    (pad "AH8" smd circle locked (at -6.8 9.2) (size 0.4 0.4) (layers "F.Cu" "F.Paste" "F.Mask")
      (net 1 "GND") (pinfunction "GND") (pintype "passive"))
    (pad "AH9" smd circle locked (at -6 9.2) (size 0.4 0.4) (layers "F.Cu" "F.Paste" "F.Mask")
      (net 302 "/FPGA power supply/VCCA0") (pinfunction "VCCA0") (pintype "passive"))
    (pad "AH11" smd circle locked (at -4.4 9.2) (size 0.4 0.4) (layers "F.Cu" "F.Paste" "F.Mask")
      (net 1 "GND") (pinfunction "GND") (pintype "passive"))
    (pad "AH12" smd circle locked (at -3.6 9.2) (size 0.4 0.4) (layers "F.Cu" "F.Paste" "F.Mask")
      (net 302 "/FPGA power supply/VCCA0") (pinfunction "VCCA0") (pintype "passive"))
    (pad "AH14" smd circle locked (at -2 9.2) (size 0.4 0.4) (layers "F.Cu" "F.Paste" "F.Mask")
      (net 1 "GND") (pinfunction "GND") (pintype "passive"))
    (pad "AH15" smd circle locked (at -1.2 9.2) (size 0.4 0.4) (layers "F.Cu" "F.Paste" "F.Mask")
      (net 1 "GND") (pinfunction "GND") (pintype "passive"))
    (pad "AH16" smd circle locked (at -0.4 9.2) (size 0.4 0.4) (layers "F.Cu" "F.Paste" "F.Mask")
      (net 1 "GND") (pinfunction "GND") (pintype "passive"))
    (pad "AH17" smd circle locked (at 0.4 9.2) (size 0.4 0.4) (layers "F.Cu" "F.Paste" "F.Mask")
      (net 1 "GND") (pinfunction "GND") (pintype "passive"))
    (pad "AH19" smd circle locked (at 2 9.2) (size 0.4 0.4) (layers "F.Cu" "F.Paste" "F.Mask")
      (net 303 "/FPGA power supply/VCCA1") (pinfunction "VCCA1") (pintype "passive"))
    (pad "AH20" smd circle locked (at 2.8 9.2) (size 0.4 0.4) (layers "F.Cu" "F.Paste" "F.Mask")
      (net 1 "GND") (pinfunction "GND") (pintype "passive"))
    (pad "AH22" smd circle locked (at 4.4 9.2) (size 0.4 0.4) (layers "F.Cu" "F.Paste" "F.Mask")
      (net 303 "/FPGA power supply/VCCA1") (pinfunction "VCCA1") (pintype "passive"))
    (pad "AH23" smd circle locked (at 5.2 9.2) (size 0.4 0.4) (layers "F.Cu" "F.Paste" "F.Mask")
      (net 1 "GND") (pinfunction "GND") (pintype "passive"))
    (pad "AH24" smd circle locked (at 6 9.2) (size 0.4 0.4) (layers "F.Cu" "F.Paste" "F.Mask")
      (net 1 "GND") (pinfunction "GND") (pintype "passive"))
    (pad "AH25" smd circle locked (at 6.8 9.2) (size 0.4 0.4) (layers "F.Cu" "F.Paste" "F.Mask")
      (net 1 "GND") (pinfunction "GND") (pintype "passive"))
    (pad "AH26" smd circle locked (at 7.6 9.2) (size 0.4 0.4) (layers "F.Cu" "F.Paste" "F.Mask")
      (net 1 "GND") (pinfunction "GND") (pintype "passive"))
    (pad "AH28" smd circle locked (at 9.2 9.2) (size 0.4 0.4) (layers "F.Cu" "F.Paste" "F.Mask")
      (net 78 "NCSI_TXD1") (pinfunction "PB112B") (pintype "bidirectional"))
    (pad "AH29" smd circle locked (at 10 9.2) (size 0.4 0.4) (layers "F.Cu" "F.Paste" "F.Mask")
      (net 1 "GND") (pinfunction "GND") (pintype "passive"))
    (pad "AH30" smd circle locked (at 10.8 9.2) (size 0.4 0.4) (layers "F.Cu" "F.Paste" "F.Mask")
      (net 79 "NCSI_RXER") (pinfunction "PB114A") (pintype "bidirectional"))
    (pad "AH31" smd circle locked (at 11.6 9.2) (size 0.4 0.4) (layers "F.Cu" "F.Paste" "F.Mask")
      (net 1 "GND") (pinfunction "GND") (pintype "passive"))
    (pad "AH32" smd circle locked (at 12.4 9.2) (size 0.4 0.4) (layers "F.Cu" "F.Paste" "F.Mask")
      (net 90 "SGPIO_INTR_N") (pinfunction "PB119A") (pintype "bidirectional"))
    (pad "AJ1" smd circle locked (at -12.4 10) (size 0.4 0.4) (layers "F.Cu" "F.Paste" "F.Mask")
      (net 431 "Net-(U21I-PB6A)") (pinfunction "PB6A") (pintype "bidirectional"))
    (pad "AJ2" smd circle locked (at -11.6 10) (size 0.4 0.4) (layers "F.Cu" "F.Paste" "F.Mask")
      (net 275 "ROT_QSPI_DQ1") (pinfunction "PB11A") (pintype "bidirectional"))
    (pad "AJ3" smd circle locked (at -10.8 10) (size 0.4 0.4) (layers "F.Cu" "F.Paste" "F.Mask")
      (net 575 "unconnected-(U21I-PB15A-PadAJ3)") (pinfunction "PB15A") (pintype "bidirectional+no_connect"))
    (pad "AJ4" smd circle locked (at -10 10) (size 0.4 0.4) (layers "F.Cu" "F.Paste" "F.Mask")
      (net 278 "DONE") (pinfunction "DONE") (pintype "bidirectional"))
    (pad "AJ5" smd circle locked (at -9.2 10) (size 0.4 0.4) (layers "F.Cu" "F.Paste" "F.Mask")
      (net 19 "JTAG_TDI") (pinfunction "TDI") (pintype "bidirectional"))
    (pad "AJ7" smd circle locked (at -7.6 10) (size 0.4 0.4) (layers "F.Cu" "F.Paste" "F.Mask")
      (net 1 "GND") (pinfunction "GND") (pintype "passive"))
    (pad "AJ8" smd circle locked (at -6.8 10) (size 0.4 0.4) (layers "F.Cu" "F.Paste" "F.Mask")
      (net 1 "GND") (pinfunction "GND") (pintype "passive"))
    (pad "AJ9" smd circle locked (at -6 10) (size 0.4 0.4) (layers "F.Cu" "F.Paste" "F.Mask")
      (net 302 "/FPGA power supply/VCCA0") (pinfunction "VCCA0") (pintype "passive"))
    (pad "AJ10" smd circle locked (at -5.2 10) (size 0.4 0.4) (layers "F.Cu" "F.Paste" "F.Mask")
      (net 302 "/FPGA power supply/VCCA0") (pinfunction "VCCA0") (pintype "passive"))
    (pad "AJ11" smd circle locked (at -4.4 10) (size 0.4 0.4) (layers "F.Cu" "F.Paste" "F.Mask")
      (net 1 "GND") (pinfunction "GND") (pintype "passive"))
    (pad "AJ12" smd circle locked (at -3.6 10) (size 0.4 0.4) (layers "F.Cu" "F.Paste" "F.Mask")
      (net 302 "/FPGA power supply/VCCA0") (pinfunction "VCCA0") (pintype "passive"))
    (pad "AJ13" smd circle locked (at -2.8 10) (size 0.4 0.4) (layers "F.Cu" "F.Paste" "F.Mask")
      (net 302 "/FPGA power supply/VCCA0") (pinfunction "VCCA0") (pintype "passive"))
    (pad "AJ14" smd circle locked (at -2 10) (size 0.4 0.4) (layers "F.Cu" "F.Paste" "F.Mask")
      (net 1 "GND") (pinfunction "GND") (pintype "passive"))
    (pad "AJ15" smd circle locked (at -1.2 10) (size 0.4 0.4) (layers "F.Cu" "F.Paste" "F.Mask")
      (net 304 "/FPGA power supply/VCCAUX") (pinfunction "VCCAUXA0") (pintype "power_in"))
    (pad "AJ16" smd circle locked (at -0.4 10) (size 0.4 0.4) (layers "F.Cu" "F.Paste" "F.Mask")
      (net 304 "/FPGA power supply/VCCAUX") (pinfunction "VCCAUXA0") (pintype "passive"))
    (pad "AJ17" smd circle locked (at 0.4 10) (size 0.4 0.4) (layers "F.Cu" "F.Paste" "F.Mask")
      (net 1 "GND") (pinfunction "GND") (pintype "passive"))
    (pad "AJ18" smd circle locked (at 1.2 10) (size 0.4 0.4) (layers "F.Cu" "F.Paste" "F.Mask")
      (net 303 "/FPGA power supply/VCCA1") (pinfunction "VCCA1") (pintype "passive"))
    (pad "AJ19" smd circle locked (at 2 10) (size 0.4 0.4) (layers "F.Cu" "F.Paste" "F.Mask")
      (net 303 "/FPGA power supply/VCCA1") (pinfunction "VCCA1") (pintype "passive"))
    (pad "AJ20" smd circle locked (at 2.8 10) (size 0.4 0.4) (layers "F.Cu" "F.Paste" "F.Mask")
      (net 1 "GND") (pinfunction "GND") (pintype "passive"))
    (pad "AJ21" smd circle locked (at 3.6 10) (size 0.4 0.4) (layers "F.Cu" "F.Paste" "F.Mask")
      (net 303 "/FPGA power supply/VCCA1") (pinfunction "VCCA1") (pintype "passive"))
    (pad "AJ22" smd circle locked (at 4.4 10) (size 0.4 0.4) (layers "F.Cu" "F.Paste" "F.Mask")
      (net 303 "/FPGA power supply/VCCA1") (pinfunction "VCCA1") (pintype "passive"))
  )
)
